(kicad_pcb
	(version 20241229)
	(generator "pcbnew")
	(generator_version "9.0")
	(general
		(thickness 1.711)
		(legacy_teardrops no)
	)
	(paper "A4")
	(title_block
		(title "Antmicro Baseboard for Jetson AGX Thor")
		(date "2026-02-18")
		(rev "1.1.0")
		(company "Antmicro Ltd")
		(comment 1 "www.antmicro.com")
		(comment 9 "footprints 196-200 of 1170")
	)
	(layers
		(0 "F.Cu" signal)
		(4 "In1.Cu" signal)
		(6 "In2.Cu" signal)
		(8 "In3.Cu" signal)
		(10 "In4.Cu" jumper)
		(12 "In5.Cu" signal)
		(14 "In6.Cu" signal)
		(16 "In7.Cu" signal)
		(18 "In8.Cu" signal)
		(2 "B.Cu" signal)
		(9 "F.Adhes" user "F.Adhesive")
		(11 "B.Adhes" user "B.Adhesive")
		(13 "F.Paste" user)
		(15 "B.Paste" user)
		(5 "F.SilkS" user "F.Silkscreen")
		(7 "B.SilkS" user "B.Silkscreen")
		(1 "F.Mask" user)
		(3 "B.Mask" user)
		(17 "Dwgs.User" user "User.Drawings")
		(19 "Cmts.User" user "User.Comments")
		(21 "Eco1.User" user "User.Eco1")
		(23 "Eco2.User" user "User.Eco2")
		(25 "Edge.Cuts" user)
		(27 "Margin" user)
		(31 "F.CrtYd" user "F.Courtyard")
		(29 "B.CrtYd" user "B.Courtyard")
		(35 "F.Fab" user)
		(33 "B.Fab" user)
	)
	(footprint "antmicro-footprints:C_0805_2012Metric"
		(layer "F.Cu")
		(at 173.17 89.11 90)
		(descr "Capacitor SMD 0805")
		(tags "capacitor SMD 0805")
		(property "Reference" "C242"
			(at -1.67 -5.57 90)
			(layer "F.SilkS")
			(effects
				(font
					(size 0.7 0.7)
					(thickness 0.15)
				)
				(justify left bottom)
			)
		)
		(property "Value" "C_22u_25V_0805"
			(at -2.055717 1.963152 90)
			(layer "F.Fab")
			(effects
				(font
					(size 0.7 0.7)
					(thickness 0.15)
				)
				(justify left bottom)
			)
		)
		(property "Datasheet" "https://product.samsungsem.com/mlcc/CL21A226MAYNNN.do"
			(at 0 0 90)
			(layer "F.Fab")
			(hide yes)
			(effects
				(font
					(size 1.27 1.27)
					(thickness 0.15)
				)
			)
		)
		(property "Description" "SMT Multilayer Ceramic Capacitor, 22uF, +/-20%, 25V, X5R, 0805 [2012 Metric]"
			(at 0 0 90)
			(layer "F.Fab")
			(hide yes)
			(effects
				(font
					(size 1.27 1.27)
					(thickness 0.15)
				)
			)
		)
		(property "MPN" "CL21A226MAYNNNE"
			(at 0 0 90)
			(unlocked yes)
			(layer "F.Fab")
			(hide yes)
			(effects
				(font
					(size 1 1)
					(thickness 0.15)
				)
			)
		)
		(property "Manufacturer" "Samsung Electro-Mechanics"
			(at 0 0 90)
			(unlocked yes)
			(layer "F.Fab")
			(hide yes)
			(effects
				(font
					(size 1 1)
					(thickness 0.15)
				)
			)
		)
		(property "License" "Apache-2.0"
			(at 0 0 90)
			(unlocked yes)
			(layer "F.Fab")
			(hide yes)
			(effects
				(font
					(size 1 1)
					(thickness 0.15)
				)
			)
		)
		(property "Author" "Antmicro"
			(at 0 0 90)
			(unlocked yes)
			(layer "F.Fab")
			(hide yes)
			(effects
				(font
					(size 1 1)
					(thickness 0.15)
				)
			)
		)
		(property "Val" "22u"
			(at 0 0 90)
			(unlocked yes)
			(layer "F.Fab")
			(hide yes)
			(effects
				(font
					(size 1 1)
					(thickness 0.15)
				)
			)
		)
		(property "Voltage" "25V"
			(at 0 0 90)
			(unlocked yes)
			(layer "F.Fab")
			(hide yes)
			(effects
				(font
					(size 1 1)
					(thickness 0.15)
				)
			)
		)
		(property "Dielectric" "X5R"
			(at 0 0 90)
			(unlocked yes)
			(layer "F.Fab")
			(hide yes)
			(effects
				(font
					(size 1 1)
					(thickness 0.15)
				)
			)
		)
		(property "Public" "False"
			(at 0 0 90)
			(unlocked yes)
			(layer "F.Fab")
			(hide yes)
			(effects
				(font
					(size 1 1)
					(thickness 0.15)
				)
			)
		)
		(component_classes
			(class "DCDC_SOM")
		)
		(sheetname "/DCDC/")
		(sheetfile "dcdc.kicad_sch")
		(attr smd)
		(fp_line
			(start -0.3 -0.7)
			(end 0.3 -0.7)
			(stroke
				(width 0.15)
				(type solid)
			)
			(layer "F.SilkS")
		)
		(fp_line
			(start -0.3 0.7)
			(end 0.3 0.7)
			(stroke
				(width 0.15)
				(type solid)
			)
			(layer "F.SilkS")
		)
		(fp_rect
			(start 1.95 -0.9)
			(end -1.95 0.9)
			(stroke
				(width 0.05)
				(type default)
			)
			(fill no)
			(layer "F.CrtYd")
		)
		(fp_rect
			(start -0.95 -0.675)
			(end 0.95 0.675)
			(stroke
				(width 0.15)
				(type solid)
			)
			(fill no)
			(layer "F.Fab")
		)
		(fp_text user "License: Apache-2.0"
			(at -1.9 4.947 90)
			(layer "F.Fab")
			(effects
				(font
					(size 0.7 0.7)
					(thickness 0.15)
				)
				(justify left bottom)
			)
		)
		(fp_text user "${REFERENCE}"
			(at -1.9 3.947 90)
			(layer "F.Fab")
			(effects
				(font
					(size 0.7 0.7)
					(thickness 0.15)
				)
				(justify left bottom)
			)
		)
		(fp_text user "Author: Antmicro"
			(at -1.9 5.947 90)
			(layer "F.Fab")
			(effects
				(font
					(size 0.7 0.7)
					(thickness 0.15)
				)
				(justify left bottom)
			)
		)
		(pad "1" smd roundrect
			(at -1.1 0 90)
			(size 1.2 1.3)
			(layers "F.Cu" "F.Mask" "F.Paste")
			(roundrect_rratio 0.25)
			(net 1 "GND")
			(pintype "passive")
		)
		(pad "2" smd roundrect
			(at 1.1 0 90)
			(size 1.2 1.3)
			(layers "F.Cu" "F.Mask" "F.Paste")
			(roundrect_rratio 0.25)
			(net 13 "VCC")
			(pintype "passive")
		)
	)
	(footprint "antmicro-footprints:TP_SMD_0.75mm"
		(layer "F.Cu")
		(at 179.75 57.19 90)
		(property "Reference" "TP5"
			(at -1.5 -0.69 90)
			(layer "F.SilkS")
			(hide yes)
			(effects
				(font
					(size 0.7 0.7)
					(thickness 0.15)
				)
				(justify left bottom)
			)
		)
		(property "Value" "TP_0.75mm_SMD"
			(at 0 1.2 90)
			(layer "F.Fab")
			(effects
				(font
					(size 0.7 0.7)
					(thickness 0.15)
				)
				(justify left bottom)
			)
		)
		(property "Description" "SMT test point"
			(at 0 0 90)
			(layer "F.Fab")
			(hide yes)
			(effects
				(font
					(size 1.27 1.27)
					(thickness 0.15)
				)
			)
		)
		(property "MPN" ""
			(at 0 0 90)
			(unlocked yes)
			(layer "F.Fab")
			(hide yes)
			(effects
				(font
					(size 1 1)
					(thickness 0.15)
				)
			)
		)
		(property "Manufacturer" ""
			(at 0 0 90)
			(unlocked yes)
			(layer "F.Fab")
			(hide yes)
			(effects
				(font
					(size 1 1)
					(thickness 0.15)
				)
			)
		)
		(property "Author" "Antmicro"
			(at 0 0 90)
			(unlocked yes)
			(layer "F.Fab")
			(hide yes)
			(effects
				(font
					(size 1 1)
					(thickness 0.15)
				)
			)
		)
		(property "License" "Apache-2.0"
			(at 0 0 90)
			(unlocked yes)
			(layer "F.Fab")
			(hide yes)
			(effects
				(font
					(size 1 1)
					(thickness 0.15)
				)
			)
		)
		(sheetname "/Power/")
		(sheetfile "power.kicad_sch")
		(attr exclude_from_pos_files exclude_from_bom)
		(fp_circle
			(center 0 0)
			(end 0.475 0)
			(stroke
				(width 0.05)
				(type default)
			)
			(fill no)
			(layer "F.CrtYd")
		)
		(fp_text user "${REFERENCE}"
			(at -0.4 2.7 90)
			(layer "F.Fab")
			(effects
				(font
					(size 0.7 0.7)
					(thickness 0.15)
				)
				(justify left bottom)
			)
		)
		(fp_text user "License: Apache-2.0"
			(at -0.4 5.101 90)
			(layer "F.Fab")
			(effects
				(font
					(size 0.7 0.7)
					(thickness 0.15)
				)
				(justify left bottom)
			)
		)
		(fp_text user "Author: Antmicro"
			(at -0.4 3.901 90)
			(layer "F.Fab")
			(effects
				(font
					(size 0.7 0.7)
					(thickness 0.15)
				)
				(justify left bottom)
			)
		)
		(pad "1" smd circle
			(at 0 0 90)
			(size 0.75 0.75)
			(layers "F.Cu" "F.Mask")
			(net 12 "SYS_VIN_HV")
			(pinfunction "1")
			(pintype "passive")
		)
	)
	(footprint "antmicro-footprints:L_WE-MAPI-4020"
		(layer "F.Cu")
		(at 191.25 130.96)
		(property "Reference" "L5"
			(at -1.05 2.54 0)
			(layer "F.SilkS")
			(effects
				(font
					(size 0.7 0.7)
					(thickness 0.15)
				)
				(justify right top)
			)
		)
		(property "Value" "L_1u8_6.8A_WE-MAPI-4020"
			(at -2.4 3.4 0)
			(layer "F.Fab")
			(effects
				(font
					(size 0.7 0.7)
					(thickness 0.15)
				)
				(justify right top)
			)
		)
		(property "Datasheet" "https://www.we-online.com/components/products/datasheet/74438356018.pdf"
			(at 0 0 0)
			(layer "F.Fab")
			(hide yes)
			(effects
				(font
					(size 1.27 1.27)
					(thickness 0.15)
				)
			)
		)
		(property "Description" "Power Inductors - SMD WE-MAPI 1.8uH 4.6A DCR=30mOhms AEC-Q200"
			(at 0 0 0)
			(layer "F.Fab")
			(hide yes)
			(effects
				(font
					(size 1.27 1.27)
					(thickness 0.15)
				)
			)
		)
		(property "Val" "1u8/6.8A"
			(at 0 0 0)
			(unlocked yes)
			(layer "F.Fab")
			(hide yes)
			(effects
				(font
					(size 1 1)
					(thickness 0.15)
				)
			)
		)
		(property "Manufacturer" "Würth Elektronik"
			(at 0 0 0)
			(unlocked yes)
			(layer "F.Fab")
			(hide yes)
			(effects
				(font
					(size 1 1)
					(thickness 0.15)
				)
			)
		)
		(property "MPN" "74438356018"
			(at 0 0 0)
			(unlocked yes)
			(layer "F.Fab")
			(hide yes)
			(effects
				(font
					(size 1 1)
					(thickness 0.15)
				)
			)
		)
		(property "ISat" "6.5 A"
			(at 0 0 0)
			(unlocked yes)
			(layer "F.Fab")
			(hide yes)
			(effects
				(font
					(size 1 1)
					(thickness 0.15)
				)
			)
		)
		(property "IMax" "6.8 A"
			(at 0 0 0)
			(unlocked yes)
			(layer "F.Fab")
			(hide yes)
			(effects
				(font
					(size 1 1)
					(thickness 0.15)
				)
			)
		)
		(property "Size" "4.1x4.1mm"
			(at 0 0 0)
			(unlocked yes)
			(layer "F.Fab")
			(hide yes)
			(effects
				(font
					(size 1 1)
					(thickness 0.15)
				)
			)
		)
		(property "Author" "Antmicro"
			(at 0 0 0)
			(unlocked yes)
			(layer "F.Fab")
			(hide yes)
			(effects
				(font
					(size 1 1)
					(thickness 0.15)
				)
			)
		)
		(property "License" "Apache-2.0"
			(at 0 0 0)
			(unlocked yes)
			(layer "F.Fab")
			(hide yes)
			(effects
				(font
					(size 1 1)
					(thickness 0.15)
				)
			)
		)
		(component_classes
			(class "DCDC_1V15")
		)
		(sheetname "/DCDC/")
		(sheetfile "dcdc.kicad_sch")
		(attr smd)
		(fp_rect
			(start -2.2 -2.2)
			(end 2.2 2.2)
			(stroke
				(width 0.15)
				(type solid)
			)
			(fill no)
			(layer "F.SilkS")
		)
		(fp_rect
			(start -2.3 -2.3)
			(end 2.3 2.3)
			(stroke
				(width 0.05)
				(type solid)
			)
			(fill no)
			(layer "F.CrtYd")
		)
		(fp_rect
			(start -2.05 -2.05)
			(end 2.05 2.05)
			(stroke
				(width 0.15)
				(type solid)
			)
			(fill no)
			(layer "F.Fab")
		)
		(fp_text user "${REFERENCE}"
			(at -2.4 7.8 0)
			(layer "F.Fab")
			(effects
				(font
					(size 0.7 0.7)
					(thickness 0.15)
				)
				(justify left bottom)
			)
		)
		(fp_text user "Author: Antmicro"
			(at -2.4 6.6 0)
			(layer "F.Fab")
			(effects
				(font
					(size 0.7 0.7)
					(thickness 0.15)
				)
				(justify left bottom)
			)
		)
		(fp_text user "License: Apache-2.0"
			(at -2.4 5.4 0)
			(layer "F.Fab")
			(effects
				(font
					(size 0.7 0.7)
					(thickness 0.15)
				)
				(justify left bottom)
			)
		)
		(pad "1" smd roundrect
			(at -1.185 0 90)
			(size 3.7 1)
			(layers "F.Cu" "F.Mask" "F.Paste")
			(roundrect_rratio 0.1)
			(net 1034 "/DCDC/1V15_SW")
			(pintype "passive")
		)
		(pad "2" smd roundrect
			(at 1.185 0 90)
			(size 3.7 1)
			(layers "F.Cu" "F.Mask" "F.Paste")
			(roundrect_rratio 0.1)
			(net 280 "/DCDC/1V15_OUT")
			(pintype "passive")
		)
	)
	(footprint "antmicro-footprints:C_0805_2012Metric"
		(layer "F.Cu")
		(at 174.98 89.11 90)
		(descr "Capacitor SMD 0805")
		(tags "capacitor SMD 0805")
		(property "Reference" "C270"
			(at -1.69 -6.38 90)
			(layer "F.SilkS")
			(effects
				(font
					(size 0.7 0.7)
					(thickness 0.15)
				)
				(justify left bottom)
			)
		)
		(property "Value" "C_22u_25V_0805"
			(at -2.055717 1.963152 90)
			(layer "F.Fab")
			(effects
				(font
					(size 0.7 0.7)
					(thickness 0.15)
				)
				(justify left bottom)
			)
		)
		(property "Datasheet" "https://product.samsungsem.com/mlcc/CL21A226MAYNNN.do"
			(at 0 0 90)
			(layer "F.Fab")
			(hide yes)
			(effects
				(font
					(size 1.27 1.27)
					(thickness 0.15)
				)
			)
		)
		(property "Description" "SMT Multilayer Ceramic Capacitor, 22uF, +/-20%, 25V, X5R, 0805 [2012 Metric]"
			(at 0 0 90)
			(layer "F.Fab")
			(hide yes)
			(effects
				(font
					(size 1.27 1.27)
					(thickness 0.15)
				)
			)
		)
		(property "MPN" "CL21A226MAYNNNE"
			(at 0 0 90)
			(unlocked yes)
			(layer "F.Fab")
			(hide yes)
			(effects
				(font
					(size 1 1)
					(thickness 0.15)
				)
			)
		)
		(property "Manufacturer" "Samsung Electro-Mechanics"
			(at 0 0 90)
			(unlocked yes)
			(layer "F.Fab")
			(hide yes)
			(effects
				(font
					(size 1 1)
					(thickness 0.15)
				)
			)
		)
		(property "License" "Apache-2.0"
			(at 0 0 90)
			(unlocked yes)
			(layer "F.Fab")
			(hide yes)
			(effects
				(font
					(size 1 1)
					(thickness 0.15)
				)
			)
		)
		(property "Author" "Antmicro"
			(at 0 0 90)
			(unlocked yes)
			(layer "F.Fab")
			(hide yes)
			(effects
				(font
					(size 1 1)
					(thickness 0.15)
				)
			)
		)
		(property "Val" "22u"
			(at 0 0 90)
			(unlocked yes)
			(layer "F.Fab")
			(hide yes)
			(effects
				(font
					(size 1 1)
					(thickness 0.15)
				)
			)
		)
		(property "Voltage" "25V"
			(at 0 0 90)
			(unlocked yes)
			(layer "F.Fab")
			(hide yes)
			(effects
				(font
					(size 1 1)
					(thickness 0.15)
				)
			)
		)
		(property "Dielectric" "X5R"
			(at 0 0 90)
			(unlocked yes)
			(layer "F.Fab")
			(hide yes)
			(effects
				(font
					(size 1 1)
					(thickness 0.15)
				)
			)
		)
		(property "Public" "False"
			(at 0 0 90)
			(unlocked yes)
			(layer "F.Fab")
			(hide yes)
			(effects
				(font
					(size 1 1)
					(thickness 0.15)
				)
			)
		)
		(component_classes
			(class "DCDC_SOM")
		)
		(sheetname "/DCDC/")
		(sheetfile "dcdc.kicad_sch")
		(attr smd)
		(fp_line
			(start -0.3 -0.7)
			(end 0.3 -0.7)
			(stroke
				(width 0.15)
				(type solid)
			)
			(layer "F.SilkS")
		)
		(fp_line
			(start -0.3 0.7)
			(end 0.3 0.7)
			(stroke
				(width 0.15)
				(type solid)
			)
			(layer "F.SilkS")
		)
		(fp_rect
			(start 1.95 -0.9)
			(end -1.95 0.9)
			(stroke
				(width 0.05)
				(type default)
			)
			(fill no)
			(layer "F.CrtYd")
		)
		(fp_rect
			(start -0.95 -0.675)
			(end 0.95 0.675)
			(stroke
				(width 0.15)
				(type solid)
			)
			(fill no)
			(layer "F.Fab")
		)
		(fp_text user "Author: Antmicro"
			(at -1.9 5.947 90)
			(layer "F.Fab")
			(effects
				(font
					(size 0.7 0.7)
					(thickness 0.15)
				)
				(justify left bottom)
			)
		)
		(fp_text user "License: Apache-2.0"
			(at -1.9 4.947 90)
			(layer "F.Fab")
			(effects
				(font
					(size 0.7 0.7)
					(thickness 0.15)
				)
				(justify left bottom)
			)
		)
		(fp_text user "${REFERENCE}"
			(at -1.9 3.947 90)
			(layer "F.Fab")
			(effects
				(font
					(size 0.7 0.7)
					(thickness 0.15)
				)
				(justify left bottom)
			)
		)
		(pad "1" smd roundrect
			(at -1.1 0 90)
			(size 1.2 1.3)
			(layers "F.Cu" "F.Mask" "F.Paste")
			(roundrect_rratio 0.25)
			(net 1 "GND")
			(pintype "passive")
		)
		(pad "2" smd roundrect
			(at 1.1 0 90)
			(size 1.2 1.3)
			(layers "F.Cu" "F.Mask" "F.Paste")
			(roundrect_rratio 0.25)
			(net 13 "VCC")
			(pintype "passive")
		)
	)
	(footprint "antmicro-footprints:R_0402_1005Metric"
		(layer "F.Cu")
		(at 216.2 77)
		(descr "Resistor SMD 0402")
		(tags "resistor SMD 0402")
		(property "Reference" "R123"
			(at 1.4 -1.4 180)
			(layer "F.SilkS")
			(effects
				(font
					(size 0.7 0.7)
					(thickness 0.15)
				)
				(justify right top)
			)
		)
		(property "Value" "R_0R_0402"
			(at -1.011843 1.772046 180)
			(layer "F.Fab")
			(effects
				(font
					(size 0.7 0.7)
					(thickness 0.15)
				)
				(justify right top)
			)
		)
		(property "Datasheet" "https://industrial.panasonic.com/cdbs/www-data/pdf/RDA0000/AOA0000C301.pdf"
			(at 0 0 180)
			(layer "F.Fab")
			(hide yes)
			(effects
				(font
					(size 1.27 1.27)
					(thickness 0.15)
				)
			)
		)
		(property "Description" "SMD Chip Resistor, Jumper, 0 ohm, 100 mW, 0402 [1005 Metric], Thick Film, General Purpose"
			(at 0 0 180)
			(layer "F.Fab")
			(hide yes)
			(effects
				(font
					(size 1.27 1.27)
					(thickness 0.15)
				)
			)
		)
		(property "Manufacturer" "Panasonic"
			(at 0 0 0)
			(unlocked yes)
			(layer "F.Fab")
			(hide yes)
			(effects
				(font
					(size 1 1)
					(thickness 0.15)
				)
			)
		)
		(property "MPN" "ERJ2GE0R00X"
			(at 0 0 0)
			(unlocked yes)
			(layer "F.Fab")
			(hide yes)
			(effects
				(font
					(size 1 1)
					(thickness 0.15)
				)
			)
		)
		(property "Val" "0R"
			(at 0 0 0)
			(unlocked yes)
			(layer "F.Fab")
			(hide yes)
			(effects
				(font
					(size 1 1)
					(thickness 0.15)
				)
			)
		)
		(property "License" "Apache-2.0"
			(at 0 0 0)
			(unlocked yes)
			(layer "F.Fab")
			(hide yes)
			(effects
				(font
					(size 1 1)
					(thickness 0.15)
				)
			)
		)
		(property "Author" "Antmicro"
			(at 0 0 0)
			(unlocked yes)
			(layer "F.Fab")
			(hide yes)
			(effects
				(font
					(size 1 1)
					(thickness 0.15)
				)
			)
		)
		(property "Tolerance" "~"
			(at 0 0 0)
			(unlocked yes)
			(layer "F.Fab")
			(hide yes)
			(effects
				(font
					(size 1 1)
					(thickness 0.15)
				)
			)
		)
		(property "Current" "1A"
			(at 0 0 0)
			(unlocked yes)
			(layer "F.Fab")
			(hide yes)
			(effects
				(font
					(size 1 1)
					(thickness 0.15)
				)
			)
		)
		(sheetname "/USB Debug, PD/")
		(sheetfile "usb_debug_pd.kicad_sch")
		(attr smd)
		(fp_poly
			(pts
				(xy -0.925 -0.47) (xy -0.925 0.47) (xy 0.925 0.47) (xy 0.925 -0.47)
			)
			(stroke
				(width 0.05)
				(type default)
			)
			(fill no)
			(layer "F.CrtYd")
		)
		(fp_poly
			(pts
				(xy -0.5 -0.25) (xy -0.5 0.25) (xy 0.5 0.25) (xy 0.5 -0.25)
			)
			(stroke
				(width 0.15)
				(type solid)
			)
			(fill no)
			(layer "F.Fab")
		)
		(fp_text user "${REFERENCE}"
			(at -0.95 3.168 180)
			(layer "F.Fab")
			(effects
				(font
					(size 0.7 0.7)
					(thickness 0.15)
				)
				(justify right top)
			)
		)
		(fp_text user "Author: Antmicro"
			(at -0.95 4.169 180)
			(layer "F.Fab")
			(effects
				(font
					(size 0.7 0.7)
					(thickness 0.15)
				)
				(justify right top)
			)
		)
		(fp_text user "License: Apache-2.0"
			(at -0.949999 5.169 180)
			(layer "F.Fab")
			(effects
				(font
					(size 0.7 0.7)
					(thickness 0.15)
				)
				(justify right top)
			)
		)
		(pad "1" smd roundrect
			(at -0.48 0)
			(size 0.59 0.64)
			(layers "F.Cu" "F.Mask" "F.Paste")
			(roundrect_rratio 0.25)
			(net 959 "/SoM_IO/UART3_DEBUG.TX")
			(pintype "passive")
		)
		(pad "2" smd roundrect
			(at 0.48 0)
			(size 0.59 0.64)
			(layers "F.Cu" "F.Mask" "F.Paste")
			(roundrect_rratio 0.25)
			(net 961 "Net-(U34-RXD)")
			(pintype "passive")
		)
	)
)
